# S9S_MB_2U (Grand Teton) — schematic netlist excerpt (pin names and nets, part order shuffled) for the footprints in the layout excerpt that follows; sources: Cadence DE-HDL packaged netlist, KiCad conversion of 03242023_DA0F0TMBIJ0_F0T_Motherboard_J_brd_V01_OCP.brd

PC1340  Q_CAP  0.1UF 25V 10% X7R  pkg 0402  page 268 : A = GND ; B = PVCCIN_CPU0_VREF
R4771  Q_RES  33.2 1% CHIP  pkg 0402LF  page 216 : A = HP_LVC3_SCM_HSC_PWRGD ; B = HP_LVC3_SCM_HSC_PWRGD_PLD
C809  Q_CAP_DIFFBUS  DIFF BUS_0.22UF 6.3V 20% X6S  pkg C0201  page 175 : \1\ = P5E_CPU1_PE1_TX_C_DP<14> ; \2\ = P5E_CPU1_PE1_TX_DP<14>

(kicad_pcb
	(version 20260206)
	(generator "pcbnew")
	(generator_version "10.0")
	(general
		(thickness 1.6)
		(legacy_teardrops no)
	)
	(paper "A4")
	(title_block
		(title "03242023_DA0F0TMBIJ0_F0T_Motherboard_J_brd_V01_OCP.brd")
		(comment 1 "Grand Teton / footprints 816-818 of 6105")
	)
	(layers
		(0 "F.Cu" signal "TOP")
		(4 "In1.Cu" signal "GND")
		(6 "In2.Cu" signal "IN1")
		(8 "In3.Cu" signal "GND1")
		(10 "In4.Cu" signal "IN2")
		(12 "In5.Cu" signal "GND2")
		(14 "In6.Cu" signal "IN3")
		(16 "In7.Cu" signal "GND3")
		(18 "In8.Cu" signal "VCC")
		(20 "In9.Cu" signal "VCC1")
		(22 "In10.Cu" signal "GND4")
		(24 "In11.Cu" signal "IN4")
		(26 "In12.Cu" signal "GND5")
		(28 "In13.Cu" signal "IN5")
		(30 "In14.Cu" signal "GND6")
		(32 "In15.Cu" signal "IN6")
		(34 "In16.Cu" signal "GND7")
		(2 "B.Cu" signal "BOTTOM")
		(9 "F.Adhes" user "F.Adhesive")
		(11 "B.Adhes" user "B.Adhesive")
		(13 "F.Paste" user "Package Geometry/Pastemask Top")
		(15 "B.Paste" user "Package Geometry/Pastemask Bottom")
		(5 "F.SilkS" user "Ref Des/Silkscreen Top")
		(7 "B.SilkS" user "Ref Des/Silkscreen Bottom")
		(1 "F.Mask" user "Board Geometry/Soldermask Top")
		(3 "B.Mask" user "Board Geometry/Soldermask Bottom")
		(17 "Dwgs.User" user "User.Drawings")
		(19 "Cmts.User" user "User.Comments")
		(21 "Eco1.User" user "User.Eco1")
		(23 "Eco2.User" user "User.Eco2")
		(25 "Edge.Cuts" user "Board Geometry/Outline")
		(27 "Margin" user)
		(31 "F.CrtYd" user "Package Geometry/Place Bound Top")
		(29 "B.CrtYd" user "Package Geometry/Place Bound Bottom")
		(35 "F.Fab" user "Ref Des/Assembly Top")
		(33 "B.Fab" user "Ref Des/Assembly Bottom")
	)
	(footprint ""
		(layer "F.Cu")
		(at 366.72139 -338.3026 -90)
		(property "Reference" "PC1340"
			(at 0 0 270)
			(layer "F.SilkS")
			(hide yes)
			(effects
				(font
					(size 1.27 1.27)
				)
			)
		)
		(property "Value" ""
			(at 0 0 270)
			(layer "F.Fab")
			(effects
				(font
					(size 1.27 1.27)
				)
			)
		)
		(duplicate_pad_numbers_are_jumpers no)
		(fp_line
			(start -0.7874 0.4064)
			(end -0.7874 -0.4064)
			(stroke
				(width 0.1524)
				(type default)
			)
			(layer "F.SilkS")
		)
		(fp_line
			(start 0.7874 0.4064)
			(end -0.7874 0.4064)
			(stroke
				(width 0.1524)
				(type default)
			)
			(layer "F.SilkS")
		)
		(fp_line
			(start -0.7874 -0.4064)
			(end 0.7874 -0.4064)
			(stroke
				(width 0.1524)
				(type default)
			)
			(layer "F.SilkS")
		)
		(fp_line
			(start 0.7874 -0.4064)
			(end 0.7874 0.4064)
			(stroke
				(width 0.1524)
				(type default)
			)
			(layer "F.SilkS")
		)
		(fp_line
			(start -0.67945 0.3048)
			(end -0.67945 -0.305054)
			(stroke
				(width 0.1)
				(type default)
			)
			(layer "F.Fab")
		)
		(fp_line
			(start -0.12065 0.3048)
			(end -0.67945 0.3048)
			(stroke
				(width 0.1)
				(type default)
			)
			(layer "F.Fab")
		)
		(fp_line
			(start 0.120396 0.3048)
			(end 0.120396 0.2794)
			(stroke
				(width 0.1)
				(type default)
			)
			(layer "F.Fab")
		)
		(fp_line
			(start 0.67945 0.3048)
			(end 0.120396 0.3048)
			(stroke
				(width 0.1)
				(type default)
			)
			(layer "F.Fab")
		)
		(fp_line
			(start -0.12065 0.2794)
			(end -0.12065 0.3048)
			(stroke
				(width 0.1)
				(type default)
			)
			(layer "F.Fab")
		)
		(fp_line
			(start 0.120396 0.2794)
			(end -0.12065 0.2794)
			(stroke
				(width 0.1)
				(type default)
			)
			(layer "F.Fab")
		)
		(fp_line
			(start -0.12065 -0.2794)
			(end 0.12065 -0.2794)
			(stroke
				(width 0.1)
				(type default)
			)
			(layer "F.Fab")
		)
		(fp_line
			(start 0.12065 -0.2794)
			(end 0.12065 -0.3048)
			(stroke
				(width 0.1)
				(type default)
			)
			(layer "F.Fab")
		)
		(fp_line
			(start 0.12065 -0.3048)
			(end 0.67945 -0.3048)
			(stroke
				(width 0.1)
				(type default)
			)
			(layer "F.Fab")
		)
		(fp_line
			(start 0.67945 -0.3048)
			(end 0.67945 0.3048)
			(stroke
				(width 0.1)
				(type default)
			)
			(layer "F.Fab")
		)
		(fp_line
			(start -0.67945 -0.305054)
			(end -0.12065 -0.305054)
			(stroke
				(width 0.1)
				(type default)
			)
			(layer "F.Fab")
		)
		(fp_line
			(start -0.12065 -0.305054)
			(end -0.12065 -0.2794)
			(stroke
				(width 0.1)
				(type default)
			)
			(layer "F.Fab")
		)
		(pad "1" smd circle
			(at -0.40005 0 270)
			(size 0 0)
			(layers "F.Cu" "F.Mask" "F.Paste")
			(net "GND")
		)
		(pad "2" smd circle
			(at 0.40005 0 270)
			(size 0 0)
			(layers "F.Cu" "F.Mask" "F.Paste")
			(net "PVCCIN_CPU0_VREF")
		)
	)
	(footprint ""
		(layer "F.Cu")
		(at 19.216878 -17.623536 90)
		(property "Reference" "C809"
			(at 0 0 90)
			(layer "F.SilkS")
			(hide yes)
			(effects
				(font
					(size 1.27 1.27)
				)
			)
		)
		(property "Value" ""
			(at 0 0 90)
			(layer "F.Fab")
			(effects
				(font
					(size 1.27 1.27)
				)
			)
		)
		(duplicate_pad_numbers_are_jumpers no)
		(fp_line
			(start 0.299974 -0.150114)
			(end 0.299974 0.150114)
			(stroke
				(width 0.1)
				(type default)
			)
			(layer "F.Fab")
		)
		(fp_line
			(start -0.299974 -0.150114)
			(end 0.299974 -0.150114)
			(stroke
				(width 0.1)
				(type default)
			)
			(layer "F.Fab")
		)
		(fp_line
			(start 0.299974 0.150114)
			(end -0.299974 0.150114)
			(stroke
				(width 0.1)
				(type default)
			)
			(layer "F.Fab")
		)
		(fp_line
			(start -0.299974 0.150114)
			(end -0.299974 -0.150114)
			(stroke
				(width 0.1)
				(type default)
			)
			(layer "F.Fab")
		)
		(pad "1" smd rect
			(at -0.2667 0 90)
			(size 0.3048 0.381)
			(layers "F.Cu" "F.Mask" "F.Paste")
			(net "P5E_CPU1_PE1_TX_C_DP<14>")
		)
		(pad "2" smd rect
			(at 0.2667 0 90)
			(size 0.3048 0.381)
			(layers "F.Cu" "F.Mask" "F.Paste")
			(net "P5E_CPU1_PE1_TX_DP<14>")
		)
	)
	(footprint ""
		(layer "F.Cu")
		(at 185.7756 -93.91015 90)
		(property "Reference" "R4771"
			(at 0 0 90)
			(layer "F.SilkS")
			(hide yes)
			(effects
				(font
					(size 1.27 1.27)
				)
			)
		)
		(property "Value" ""
			(at 0 0 90)
			(layer "F.Fab")
			(effects
				(font
					(size 1.27 1.27)
				)
			)
		)
		(duplicate_pad_numbers_are_jumpers no)
		(fp_line
			(start 0.7874 -0.4064)
			(end 0.7874 0.4064)
			(stroke
				(width 0.1524)
				(type default)
			)
			(layer "F.SilkS")
		)
		(fp_line
			(start -0.7874 -0.4064)
			(end 0.7874 -0.4064)
			(stroke
				(width 0.1524)
				(type default)
			)
			(layer "F.SilkS")
		)
		(fp_line
			(start 0.7874 0.4064)
			(end -0.7874 0.4064)
			(stroke
				(width 0.1524)
				(type default)
			)
			(layer "F.SilkS")
		)
		(fp_line
			(start -0.7874 0.4064)
			(end -0.7874 -0.4064)
			(stroke
				(width 0.1524)
				(type default)
			)
			(layer "F.SilkS")
		)
		(fp_line
			(start -0.12065 -0.305054)
			(end -0.12065 -0.2794)
			(stroke
				(width 0.1)
				(type default)
			)
			(layer "F.Fab")
		)
		(fp_line
			(start -0.67945 -0.305054)
			(end -0.12065 -0.305054)
			(stroke
				(width 0.1)
				(type default)
			)
			(layer "F.Fab")
		)
		(fp_line
			(start 0.67945 -0.3048)
			(end 0.67945 0.3048)
			(stroke
				(width 0.1)
				(type default)
			)
			(layer "F.Fab")
		)
		(fp_line
			(start 0.12065 -0.3048)
			(end 0.67945 -0.3048)
			(stroke
				(width 0.1)
				(type default)
			)
			(layer "F.Fab")
		)
		(fp_line
			(start 0.12065 -0.2794)
			(end 0.12065 -0.3048)
			(stroke
				(width 0.1)
				(type default)
			)
			(layer "F.Fab")
		)
		(fp_line
			(start -0.12065 -0.2794)
			(end 0.12065 -0.2794)
			(stroke
				(width 0.1)
				(type default)
			)
			(layer "F.Fab")
		)
		(fp_line
			(start 0.120396 0.2794)
			(end -0.12065 0.2794)
			(stroke
				(width 0.1)
				(type default)
			)
			(layer "F.Fab")
		)
		(fp_line
			(start -0.12065 0.2794)
			(end -0.12065 0.3048)
			(stroke
				(width 0.1)
				(type default)
			)
			(layer "F.Fab")
		)
		(fp_line
			(start 0.67945 0.3048)
			(end 0.120396 0.3048)
			(stroke
				(width 0.1)
				(type default)
			)
			(layer "F.Fab")
		)
		(fp_line
			(start 0.120396 0.3048)
			(end 0.120396 0.2794)
			(stroke
				(width 0.1)
				(type default)
			)
			(layer "F.Fab")
		)
		(fp_line
			(start -0.12065 0.3048)
			(end -0.67945 0.3048)
			(stroke
				(width 0.1)
				(type default)
			)
			(layer "F.Fab")
		)
		(fp_line
			(start -0.67945 0.3048)
			(end -0.67945 -0.305054)
			(stroke
				(width 0.1)
				(type default)
			)
			(layer "F.Fab")
		)
		(pad "1" smd circle
			(at -0.40005 0 90)
			(size 0 0)
			(layers "F.Cu" "F.Mask" "F.Paste")
			(net "HP_LVC3_SCM_HSC_PWRGD")
		)
		(pad "2" smd circle
			(at 0.40005 0 90)
			(size 0 0)
			(layers "F.Cu" "F.Mask" "F.Paste")
			(net "HP_LVC3_SCM_HSC_PWRGD_PLD")
		)
	)
)
